# T6G (Grand Teton) — schematic netlist excerpt (pin names and nets, part order shuffled) for the footprints in the layout excerpt that follows; sources: Cadence DE-HDL packaged netlist, KiCad conversion of 04192023_DAF0TMB3IC0_F0TG_MB_C_brd_V02_OCP.brd

C332  Q_CAP  10UF 6.3V 20% X6S  pkg C0402  page 334 : A = P0V9_CPU1_RT1_2A ; B = GND
C6099  Q_CAP  1PF 50V 0.05P COG  pkg C0402  page 179 : A = P3V3_AUX_CPU0_USB2_AVDD33 ; B = GND

(kicad_pcb
	(version 20260206)
	(generator "pcbnew")
	(generator_version "10.0")
	(general
		(thickness 1.6)
		(legacy_teardrops no)
	)
	(paper "A4")
	(title_block
		(title "04192023_DAF0TMB3IC0_F0TG_MB_C_brd_V02_OCP.brd")
		(comment 1 "Grand Teton / footprints 6989-6990 of 8354")
	)
	(layers
		(0 "F.Cu" signal "TOP")
		(4 "In1.Cu" signal "GND")
		(6 "In2.Cu" signal "IN1")
		(8 "In3.Cu" signal "GND1")
		(10 "In4.Cu" signal "IN2")
		(12 "In5.Cu" signal "GND2")
		(14 "In6.Cu" signal "IN3")
		(16 "In7.Cu" signal "GND3")
		(18 "In8.Cu" signal "VCC")
		(20 "In9.Cu" signal "VCC1")
		(22 "In10.Cu" signal "GND4")
		(24 "In11.Cu" signal "IN4")
		(26 "In12.Cu" signal "GND5")
		(28 "In13.Cu" signal "IN5")
		(30 "In14.Cu" signal "GND6")
		(32 "In15.Cu" signal "IN6")
		(34 "In16.Cu" signal "GND7")
		(2 "B.Cu" signal "BOTTOM")
		(9 "F.Adhes" user "F.Adhesive")
		(11 "B.Adhes" user "B.Adhesive")
		(13 "F.Paste" user "Package Geometry/Pastemask Top")
		(15 "B.Paste" user "Package Geometry/Pastemask Bottom")
		(5 "F.SilkS" user "Ref Des/Silkscreen Top")
		(7 "B.SilkS" user "Ref Des/Silkscreen Bottom")
		(1 "F.Mask" user "Board Geometry/Soldermask Top")
		(3 "B.Mask" user "Board Geometry/Soldermask Bottom")
		(17 "Dwgs.User" user "User.Drawings")
		(19 "Cmts.User" user "User.Comments")
		(21 "Eco1.User" user "User.Eco1")
		(23 "Eco2.User" user "User.Eco2")
		(25 "Edge.Cuts" user "Board Geometry/Outline")
		(27 "Margin" user)
		(31 "F.CrtYd" user "Package Geometry/Place Bound Top")
		(29 "B.CrtYd" user "Package Geometry/Place Bound Bottom")
		(35 "F.Fab" user "Ref Des/Assembly Top")
		(33 "B.Fab" user "Ref Des/Assembly Bottom")
	)
	(footprint ""
		(layer "B.Cu")
		(at 79.918814 -390.560052 90)
		(property "Reference" "C332"
			(at 0 0 90)
			(layer "B.SilkS")
			(hide yes)
			(effects
				(font
					(size 1.27 1.27)
				)
				(justify mirror)
			)
		)
		(property "Value" ""
			(at 0 0 90)
			(layer "B.Fab")
			(effects
				(font
					(size 1.27 1.27)
				)
				(justify mirror)
			)
		)
		(duplicate_pad_numbers_are_jumpers no)
		(fp_line
			(start 0.7874 -0.4064)
			(end -0.7874 -0.4064)
			(stroke
				(width 0.1524)
				(type default)
			)
			(layer "B.SilkS")
		)
		(fp_line
			(start -0.7874 -0.4064)
			(end -0.7874 0.4064)
			(stroke
				(width 0.1524)
				(type default)
			)
			(layer "B.SilkS")
		)
		(fp_line
			(start 0.7874 0.4064)
			(end 0.7874 -0.4064)
			(stroke
				(width 0.1524)
				(type default)
			)
			(layer "B.SilkS")
		)
		(fp_line
			(start -0.7874 0.4064)
			(end 0.7874 0.4064)
			(stroke
				(width 0.1524)
				(type default)
			)
			(layer "B.SilkS")
		)
		(fp_line
			(start 0.67945 -0.305054)
			(end 0.12065 -0.305054)
			(stroke
				(width 0.1)
				(type default)
			)
			(layer "B.Fab")
		)
		(fp_line
			(start 0.12065 -0.305054)
			(end 0.12065 -0.2794)
			(stroke
				(width 0.1)
				(type default)
			)
			(layer "B.Fab")
		)
		(fp_line
			(start -0.12065 -0.3048)
			(end -0.67945 -0.3048)
			(stroke
				(width 0.1)
				(type default)
			)
			(layer "B.Fab")
		)
		(fp_line
			(start -0.67945 -0.3048)
			(end -0.67945 0.3048)
			(stroke
				(width 0.1)
				(type default)
			)
			(layer "B.Fab")
		)
		(fp_line
			(start 0.12065 -0.2794)
			(end -0.12065 -0.2794)
			(stroke
				(width 0.1)
				(type default)
			)
			(layer "B.Fab")
		)
		(fp_line
			(start -0.12065 -0.2794)
			(end -0.12065 -0.3048)
			(stroke
				(width 0.1)
				(type default)
			)
			(layer "B.Fab")
		)
		(fp_line
			(start 0.12065 0.2794)
			(end 0.12065 0.3048)
			(stroke
				(width 0.1)
				(type default)
			)
			(layer "B.Fab")
		)
		(fp_line
			(start -0.120396 0.2794)
			(end 0.12065 0.2794)
			(stroke
				(width 0.1)
				(type default)
			)
			(layer "B.Fab")
		)
		(fp_line
			(start 0.67945 0.3048)
			(end 0.67945 -0.305054)
			(stroke
				(width 0.1)
				(type default)
			)
			(layer "B.Fab")
		)
		(fp_line
			(start 0.12065 0.3048)
			(end 0.67945 0.3048)
			(stroke
				(width 0.1)
				(type default)
			)
			(layer "B.Fab")
		)
		(fp_line
			(start -0.120396 0.3048)
			(end -0.120396 0.2794)
			(stroke
				(width 0.1)
				(type default)
			)
			(layer "B.Fab")
		)
		(fp_line
			(start -0.67945 0.3048)
			(end -0.120396 0.3048)
			(stroke
				(width 0.1)
				(type default)
			)
			(layer "B.Fab")
		)
		(pad "1" smd circle
			(at 0.40005 0 270)
			(size 0 0)
			(layers "B.Cu" "B.Mask" "B.Paste")
			(net "P0V9_CPU1_RT1_2A")
		)
		(pad "2" smd circle
			(at -0.40005 0 270)
			(size 0 0)
			(layers "B.Cu" "B.Mask" "B.Paste")
			(net "GND")
		)
	)
	(footprint ""
		(layer "B.Cu")
		(at 108.089192 -29.55544 -90)
		(property "Reference" "C6099"
			(at 0 0 90)
			(layer "B.SilkS")
			(hide yes)
			(effects
				(font
					(size 1.27 1.27)
				)
				(justify mirror)
			)
		)
		(property "Value" ""
			(at 0 0 90)
			(layer "B.Fab")
			(effects
				(font
					(size 1.27 1.27)
				)
				(justify mirror)
			)
		)
		(duplicate_pad_numbers_are_jumpers no)
		(fp_line
			(start -0.7874 0.4064)
			(end 0.7874 0.4064)
			(stroke
				(width 0.1524)
				(type default)
			)
			(layer "B.SilkS")
		)
		(fp_line
			(start 0.7874 0.4064)
			(end 0.7874 -0.4064)
			(stroke
				(width 0.1524)
				(type default)
			)
			(layer "B.SilkS")
		)
		(fp_line
			(start -0.7874 -0.4064)
			(end -0.7874 0.4064)
			(stroke
				(width 0.1524)
				(type default)
			)
			(layer "B.SilkS")
		)
		(fp_line
			(start 0.7874 -0.4064)
			(end -0.7874 -0.4064)
			(stroke
				(width 0.1524)
				(type default)
			)
			(layer "B.SilkS")
		)
		(fp_line
			(start -0.67945 0.3048)
			(end -0.120396 0.3048)
			(stroke
				(width 0.1)
				(type default)
			)
			(layer "B.Fab")
		)
		(fp_line
			(start -0.120396 0.3048)
			(end -0.120396 0.2794)
			(stroke
				(width 0.1)
				(type default)
			)
			(layer "B.Fab")
		)
		(fp_line
			(start 0.12065 0.3048)
			(end 0.67945 0.3048)
			(stroke
				(width 0.1)
				(type default)
			)
			(layer "B.Fab")
		)
		(fp_line
			(start 0.67945 0.3048)
			(end 0.67945 -0.305054)
			(stroke
				(width 0.1)
				(type default)
			)
			(layer "B.Fab")
		)
		(fp_line
			(start -0.120396 0.2794)
			(end 0.12065 0.2794)
			(stroke
				(width 0.1)
				(type default)
			)
			(layer "B.Fab")
		)
		(fp_line
			(start 0.12065 0.2794)
			(end 0.12065 0.3048)
			(stroke
				(width 0.1)
				(type default)
			)
			(layer "B.Fab")
		)
		(fp_line
			(start -0.12065 -0.2794)
			(end -0.12065 -0.3048)
			(stroke
				(width 0.1)
				(type default)
			)
			(layer "B.Fab")
		)
		(fp_line
			(start 0.12065 -0.2794)
			(end -0.12065 -0.2794)
			(stroke
				(width 0.1)
				(type default)
			)
			(layer "B.Fab")
		)
		(fp_line
			(start -0.67945 -0.3048)
			(end -0.67945 0.3048)
			(stroke
				(width 0.1)
				(type default)
			)
			(layer "B.Fab")
		)
		(fp_line
			(start -0.12065 -0.3048)
			(end -0.67945 -0.3048)
			(stroke
				(width 0.1)
				(type default)
			)
			(layer "B.Fab")
		)
		(fp_line
			(start 0.12065 -0.305054)
			(end 0.12065 -0.2794)
			(stroke
				(width 0.1)
				(type default)
			)
			(layer "B.Fab")
		)
		(fp_line
			(start 0.67945 -0.305054)
			(end 0.12065 -0.305054)
			(stroke
				(width 0.1)
				(type default)
			)
			(layer "B.Fab")
		)
		(pad "1" smd circle
			(at 0.40005 0 90)
			(size 0 0)
			(layers "B.Cu" "B.Mask" "B.Paste")
			(net "P3V3_AUX_CPU0_USB2_AVDD33")
		)
		(pad "2" smd circle
			(at -0.40005 0 90)
			(size 0 0)
			(layers "B.Cu" "B.Mask" "B.Paste")
			(net "GND")
		)
	)
)
